(kicad_pcb
	(version 20260206)
	(generator "pcbnew")
	(generator_version "10.0")
	(general
		(thickness 1.6)
		(legacy_teardrops no)
	)
	(paper "A4")
	(title_block
		(title "12092022_DA0F0TMDCD0_F0T_Management_Board_D_brd_V3_OCP.brd")
		(comment 1 "Grand Teton / footprints 628-632 of 1440")
	)
	(layers
		(0 "F.Cu" signal "TOP")
		(4 "In1.Cu" signal "GND")
		(6 "In2.Cu" signal "IN1")
		(8 "In3.Cu" signal "GND1")
		(10 "In4.Cu" signal "IN2")
		(12 "In5.Cu" signal "VCC")
		(14 "In6.Cu" signal "VCC1")
		(16 "In7.Cu" signal "IN3")
		(18 "In8.Cu" signal "GND2")
		(20 "In9.Cu" signal "IN4")
		(22 "In10.Cu" signal "GND3")
		(2 "B.Cu" signal "BOTTOM")
		(9 "F.Adhes" user "F.Adhesive")
		(11 "B.Adhes" user "B.Adhesive")
		(13 "F.Paste" user "Package Geometry/Pastemask Top")
		(15 "B.Paste" user "Package Geometry/Pastemask Bottom")
		(5 "F.SilkS" user "Ref Des/Silkscreen Top")
		(7 "B.SilkS" user "Ref Des/Silkscreen Bottom")
		(1 "F.Mask" user "Board Geometry/Soldermask Top")
		(3 "B.Mask" user "Board Geometry/Soldermask Bottom")
		(17 "Dwgs.User" user "User.Drawings")
		(19 "Cmts.User" user "User.Comments")
		(21 "Eco1.User" user "User.Eco1")
		(23 "Eco2.User" user "User.Eco2")
		(25 "Edge.Cuts" user "Board Geometry/Outline")
		(27 "Margin" user)
		(31 "F.CrtYd" user "Package Geometry/Place Bound Top")
		(29 "B.CrtYd" user "Package Geometry/Place Bound Bottom")
		(35 "F.Fab" user "Ref Des/Assembly Top")
		(33 "B.Fab" user "Ref Des/Assembly Bottom")
	)
	(footprint ""
		(layer "F.Cu")
		(at 19.1516 -58.7756 90)
		(property "Reference" "R766"
			(at 0 0 90)
			(layer "F.SilkS")
			(hide yes)
			(effects
				(font
					(size 1.27 1.27)
				)
			)
		)
		(property "Value" ""
			(at 0 0 90)
			(layer "F.Fab")
			(effects
				(font
					(size 1.27 1.27)
				)
			)
		)
		(duplicate_pad_numbers_are_jumpers no)
		(fp_line
			(start 0.7874 -0.4064)
			(end 0.7874 0.4064)
			(stroke
				(width 0.1524)
				(type default)
			)
			(layer "F.SilkS")
		)
		(fp_line
			(start -0.7874 -0.4064)
			(end 0.7874 -0.4064)
			(stroke
				(width 0.1524)
				(type default)
			)
			(layer "F.SilkS")
		)
		(fp_line
			(start 0.7874 0.4064)
			(end -0.7874 0.4064)
			(stroke
				(width 0.1524)
				(type default)
			)
			(layer "F.SilkS")
		)
		(fp_line
			(start -0.7874 0.4064)
			(end -0.7874 -0.4064)
			(stroke
				(width 0.1524)
				(type default)
			)
			(layer "F.SilkS")
		)
		(fp_line
			(start -0.12065 -0.305054)
			(end -0.12065 -0.2794)
			(stroke
				(width 0.1)
				(type default)
			)
			(layer "F.Fab")
		)
		(fp_line
			(start -0.67945 -0.305054)
			(end -0.12065 -0.305054)
			(stroke
				(width 0.1)
				(type default)
			)
			(layer "F.Fab")
		)
		(fp_line
			(start 0.67945 -0.3048)
			(end 0.67945 0.3048)
			(stroke
				(width 0.1)
				(type default)
			)
			(layer "F.Fab")
		)
		(fp_line
			(start 0.12065 -0.3048)
			(end 0.67945 -0.3048)
			(stroke
				(width 0.1)
				(type default)
			)
			(layer "F.Fab")
		)
		(fp_line
			(start 0.12065 -0.2794)
			(end 0.12065 -0.3048)
			(stroke
				(width 0.1)
				(type default)
			)
			(layer "F.Fab")
		)
		(fp_line
			(start -0.12065 -0.2794)
			(end 0.12065 -0.2794)
			(stroke
				(width 0.1)
				(type default)
			)
			(layer "F.Fab")
		)
		(fp_line
			(start 0.120396 0.2794)
			(end -0.12065 0.2794)
			(stroke
				(width 0.1)
				(type default)
			)
			(layer "F.Fab")
		)
		(fp_line
			(start -0.12065 0.2794)
			(end -0.12065 0.3048)
			(stroke
				(width 0.1)
				(type default)
			)
			(layer "F.Fab")
		)
		(fp_line
			(start 0.67945 0.3048)
			(end 0.120396 0.3048)
			(stroke
				(width 0.1)
				(type default)
			)
			(layer "F.Fab")
		)
		(fp_line
			(start 0.120396 0.3048)
			(end 0.120396 0.2794)
			(stroke
				(width 0.1)
				(type default)
			)
			(layer "F.Fab")
		)
		(fp_line
			(start -0.12065 0.3048)
			(end -0.67945 0.3048)
			(stroke
				(width 0.1)
				(type default)
			)
			(layer "F.Fab")
		)
		(fp_line
			(start -0.67945 0.3048)
			(end -0.67945 -0.305054)
			(stroke
				(width 0.1)
				(type default)
			)
			(layer "F.Fab")
		)
		(pad "1" smd circle
			(at -0.40005 0 90)
			(size 0 0)
			(layers "F.Cu" "F.Mask" "F.Paste")
			(net "UART_BMC_5_RXD_BUF1")
		)
		(pad "2" smd circle
			(at 0.40005 0 90)
			(size 0 0)
			(layers "F.Cu" "F.Mask" "F.Paste")
			(net "UART_BMC_5_RXD_BUF1_SW")
		)
	)
	(footprint ""
		(layer "F.Cu")
		(at 7.059676 -49.979834 180)
		(property "Reference" "PU38"
			(at 3.122168 -3.362452 0)
			(unlocked yes)
			(layer "F.SilkS")
			(effects
				(font
					(size 0.7874 0.5842)
					(thickness 0.1524)
				)
				(justify left)
			)
		)
		(property "Value" ""
			(at 0 0 180)
			(layer "F.Fab")
			(effects
				(font
					(size 1.27 1.27)
				)
			)
		)
		(duplicate_pad_numbers_are_jumpers no)
		(fp_line
			(start 1.549908 2.050034)
			(end 1.549908 1.9304)
			(stroke
				(width 0.1524)
				(type default)
			)
			(layer "F.SilkS")
		)
		(fp_line
			(start 1.549908 -1.9812)
			(end 1.549908 -2.050034)
			(stroke
				(width 0.1524)
				(type default)
			)
			(layer "F.SilkS")
		)
		(fp_line
			(start 1.549908 -2.050034)
			(end 0.5842 -2.050034)
			(stroke
				(width 0.1524)
				(type default)
			)
			(layer "F.SilkS")
		)
		(fp_line
			(start 0 2.050034)
			(end 1.549908 2.050034)
			(stroke
				(width 0.1524)
				(type default)
			)
			(layer "F.SilkS")
		)
		(fp_line
			(start -0.5842 -2.050034)
			(end -1.549908 -2.050034)
			(stroke
				(width 0.1524)
				(type default)
			)
			(layer "F.SilkS")
		)
		(fp_line
			(start -1.549908 2.050034)
			(end -0.5842 2.050034)
			(stroke
				(width 0.1524)
				(type default)
			)
			(layer "F.SilkS")
		)
		(fp_line
			(start -1.549908 1.9812)
			(end -1.549908 2.050034)
			(stroke
				(width 0.1524)
				(type default)
			)
			(layer "F.SilkS")
		)
		(fp_line
			(start -1.549908 -2.050034)
			(end -1.549908 -1.9812)
			(stroke
				(width 0.1524)
				(type default)
			)
			(layer "F.SilkS")
		)
		(fp_poly
			(pts
				(xy -2.9464 -2.208022) (xy -2.9464 -1.192022) (xy -1.9304 -1.700022)
			)
			(stroke
				(width 0)
				(type default)
			)
			(fill yes)
			(layer "F.SilkS")
		)
		(fp_line
			(start 1.549908 2.050034)
			(end 1.549908 -2.050034)
			(stroke
				(width 0.1)
				(type default)
			)
			(layer "F.Fab")
		)
		(fp_line
			(start 1.549908 -2.050034)
			(end -1.549908 -2.050034)
			(stroke
				(width 0.1)
				(type default)
			)
			(layer "F.Fab")
		)
		(fp_line
			(start -1.549908 2.050034)
			(end 1.549908 2.050034)
			(stroke
				(width 0.1)
				(type default)
			)
			(layer "F.Fab")
		)
		(fp_line
			(start -1.549908 -2.050034)
			(end -1.549908 2.050034)
			(stroke
				(width 0.1)
				(type default)
			)
			(layer "F.Fab")
		)
		(fp_poly
			(pts
				(xy -2.9464 -2.208022) (xy -2.9464 -1.192022) (xy -1.9304 -1.700022)
			)
			(stroke
				(width 0)
				(type default)
			)
			(fill yes)
			(layer "F.Fab")
		)
		(pad "1" smd circle
			(at -1.35001 -1.700022 180)
			(size 0 0)
			(layers "F.Cu" "F.Mask" "F.Paste")
			(net "SW_P5V_AUX_BST")
		)
		(pad "2" smd rect
			(at -1.400048 -1.199896 270)
			(size 0.1778 0.8128)
			(layers "F.Cu" "F.Mask" "F.Paste")
			(net "GND")
		)
		(pad "3" smd rect
			(at -1.400048 -0.8001 270)
			(size 0.1778 0.8128)
			(layers "F.Cu" "F.Mask" "F.Paste")
			(net "P5V_AUX_CS")
		)
		(pad "4" smd rect
			(at -1.400048 -0.40005 270)
			(size 0.1778 0.8128)
			(layers "F.Cu" "F.Mask" "F.Paste")
			(net "GND")
		)
		(pad "5" smd rect
			(at -1.400048 0 270)
			(size 0.1778 0.8128)
			(layers "F.Cu" "F.Mask" "F.Paste")
			(net "P5V_AUX_REF")
		)
		(pad "6" smd rect
			(at -1.400048 0.40005 270)
			(size 0.1778 0.8128)
			(layers "F.Cu" "F.Mask" "F.Paste")
			(net "GND")
		)
		(pad "7" smd rect
			(at -1.400048 0.8001 270)
			(size 0.1778 0.8128)
			(layers "F.Cu" "F.Mask" "F.Paste")
			(net "P5V_AUX_FB")
		)
		(pad "8" smd rect
			(at -1.400048 1.199896 270)
			(size 0.1778 0.8128)
			(layers "F.Cu" "F.Mask" "F.Paste")
			(net "EN_P5V_AUX")
		)
		(pad "9" smd rect
			(at -1.400048 1.700022 270)
			(size 0.3048 0.8128)
			(layers "F.Cu" "F.Mask" "F.Paste")
			(net "PWRGD_P5V_AUX_R")
		)
		(pad "10" smd rect
			(at -0.299974 1.299972 180)
			(size 0.3048 2.0066)
			(layers "F.Cu" "F.Mask" "F.Paste")
			(net "SW_P5V_AUX_FLT")
		)
		(pad "11_18" smd circle
			(at 1.175004 0.275082 180)
			(size 0 0)
			(layers "F.Cu" "F.Mask" "F.Paste")
			(net "GND")
		)
		(pad "19" smd rect
			(at 1.400048 -1.700022 90)
			(size 0.3048 0.8128)
			(layers "F.Cu" "F.Mask" "F.Paste")
			(net "P5V_AUX_VCC")
		)
		(pad "20" smd rect
			(at 0.299974 -1.299972 180)
			(size 0.3048 2.0066)
			(layers "F.Cu" "F.Mask" "F.Paste")
			(net "SW_P5V_AUX_SW")
		)
		(pad "21" smd rect
			(at -0.299974 -1.299972 180)
			(size 0.3048 2.0066)
			(layers "F.Cu" "F.Mask" "F.Paste")
			(net "SW_P5V_AUX_FLT")
		)
	)
	(footprint ""
		(layer "F.Cu")
		(at 112.014 -24.384 90)
		(property "Reference" "X12"
			(at 0.3175 5.37337 90)
			(unlocked yes)
			(layer "F.SilkS")
			(effects
				(font
					(size 0.7874 0.5842)
					(thickness 0.1524)
				)
				(justify left)
			)
		)
		(property "Value" ""
			(at 0 0 90)
			(layer "F.Fab")
			(effects
				(font
					(size 1.27 1.27)
				)
			)
		)
		(property "Device Type" "TP_TDR_4P_FTS_TH-TP_TDR_4P_DIPA"
			(at 1.30175 1.27 180)
			(unlocked yes)
			(layer "F.Fab")
			(hide yes)
			(effects
				(font
					(size 0.635 0.4064)
					(thickness 0.1524)
				)
			)
		)
		(property "User Part Number" "N_A"
			(at 1.30175 1.27 180)
			(unlocked yes)
			(layer "Cmts.User")
			(hide yes)
			(effects
				(font
					(size 0.635 0.4064)
					(thickness 0.1524)
				)
			)
		)
		(duplicate_pad_numbers_are_jumpers no)
		(fp_line
			(start 2.54 -1.27)
			(end 0 -1.27)
			(stroke
				(width 0.1524)
				(type default)
			)
			(layer "F.SilkS")
		)
		(fp_line
			(start 0 -1.27)
			(end 0 -0.635)
			(stroke
				(width 0.1524)
				(type default)
			)
			(layer "F.SilkS")
		)
		(fp_line
			(start 2.54 -1.1303)
			(end 2.54 -1.27)
			(stroke
				(width 0.1524)
				(type default)
			)
			(layer "F.SilkS")
		)
		(fp_line
			(start 0 0.635)
			(end 0 1.905)
			(stroke
				(width 0.1524)
				(type default)
			)
			(layer "F.SilkS")
		)
		(fp_line
			(start 2.54 1.4097)
			(end 2.54 1.1303)
			(stroke
				(width 0.1524)
				(type default)
			)
			(layer "F.SilkS")
		)
		(fp_line
			(start 0 3.175)
			(end 0 3.81)
			(stroke
				(width 0.1524)
				(type default)
			)
			(layer "F.SilkS")
		)
		(fp_line
			(start 2.54 3.81)
			(end 2.54 3.6703)
			(stroke
				(width 0.1524)
				(type default)
			)
			(layer "F.SilkS")
		)
		(fp_line
			(start 0 3.81)
			(end 2.54 3.81)
			(stroke
				(width 0.1524)
				(type default)
			)
			(layer "F.SilkS")
		)
		(fp_poly
			(pts
				(xy -0.761746 0) (xy -2.285746 -0.762) (xy -2.285746 0.762)
			)
			(stroke
				(width 0)
				(type default)
			)
			(fill yes)
			(layer "F.SilkS")
		)
		(fp_line
			(start 2.54 -1.27)
			(end 0 -1.27)
			(stroke
				(width 0.1)
				(type default)
			)
			(layer "F.Fab")
		)
		(fp_line
			(start 0 -1.27)
			(end 0 3.81)
			(stroke
				(width 0.1)
				(type default)
			)
			(layer "F.Fab")
		)
		(fp_line
			(start 2.54 3.81)
			(end 2.54 -1.27)
			(stroke
				(width 0.1)
				(type default)
			)
			(layer "F.Fab")
		)
		(fp_line
			(start 0 3.81)
			(end 2.54 3.81)
			(stroke
				(width 0.1)
				(type default)
			)
			(layer "F.Fab")
		)
		(fp_poly
			(pts
				(xy -0.761746 0) (xy -2.285746 -0.762) (xy -2.285746 0.762)
			)
			(stroke
				(width 0)
				(type default)
			)
			(fill yes)
			(layer "F.Fab")
		)
		(pad "1" thru_hole circle
			(at 0 0 90)
			(size 1.0033 1.0033)
			(drill 0.249936)
			(layers "*.Cu" "*.Mask")
			(remove_unused_layers no)
			(net "TDR_DIFF_85_BOT_DN")
			(clearance 0.10795)
			(thermal_gap 0.10795)
			(padstack
				(mode front_inner_back)
				(layer "Inner"
					(shape circle)
					(size 0.8001 0.8001)
					(clearance 0.1524)
				)
				(layer "B.Cu"
					(shape circle)
					(size 1.0033 1.0033)
					(clearance 0.10795)
				)
			)
		)
		(pad "2" thru_hole circle
			(at 2.54 0 90)
			(size 1.9939 1.9939)
			(drill 0.249936)
			(layers "*.Cu" "*.Mask")
			(remove_unused_layers no)
			(net "GND_P1")
			(clearance 0.10795)
			(thermal_gap 0.10795)
			(padstack
				(mode front_inner_back)
				(layer "Inner"
					(shape circle)
					(size 0.8001 0.8001)
					(clearance 0.1524)
				)
				(layer "B.Cu"
					(shape circle)
					(size 1.9939 1.9939)
					(clearance 0.10795)
				)
			)
		)
		(pad "3" thru_hole circle
			(at 2.54 2.54 90)
			(size 1.9939 1.9939)
			(drill 0.249936)
			(layers "*.Cu" "*.Mask")
			(remove_unused_layers no)
			(net "GND_P1")
			(clearance 0.10795)
			(thermal_gap 0.10795)
			(padstack
				(mode front_inner_back)
				(layer "Inner"
					(shape circle)
					(size 0.8001 0.8001)
					(clearance 0.1524)
				)
				(layer "B.Cu"
					(shape circle)
					(size 1.9939 1.9939)
					(clearance 0.10795)
				)
			)
		)
		(pad "4" thru_hole circle
			(at 0 2.54 90)
			(size 1.0033 1.0033)
			(drill 0.249936)
			(layers "*.Cu" "*.Mask")
			(remove_unused_layers no)
			(net "TDR_DIFF_85_BOT_DP")
			(clearance 0.10795)
			(thermal_gap 0.10795)
			(padstack
				(mode front_inner_back)
				(layer "Inner"
					(shape circle)
					(size 0.8001 0.8001)
					(clearance 0.1524)
				)
				(layer "B.Cu"
					(shape circle)
					(size 1.0033 1.0033)
					(clearance 0.10795)
				)
			)
		)
	)
	(footprint ""
		(layer "F.Cu")
		(at 40.10787 -38.881558 180)
		(property "Reference" "R173"
			(at 0 0 180)
			(layer "F.SilkS")
			(hide yes)
			(effects
				(font
					(size 1.27 1.27)
				)
			)
		)
		(property "Value" ""
			(at 0 0 180)
			(layer "F.Fab")
			(effects
				(font
					(size 1.27 1.27)
				)
			)
		)
		(duplicate_pad_numbers_are_jumpers no)
		(fp_line
			(start 0.7874 0.4064)
			(end -0.7874 0.4064)
			(stroke
				(width 0.1524)
				(type default)
			)
			(layer "F.SilkS")
		)
		(fp_line
			(start 0.7874 -0.4064)
			(end 0.7874 0.4064)
			(stroke
				(width 0.1524)
				(type default)
			)
			(layer "F.SilkS")
		)
		(fp_line
			(start -0.7874 0.4064)
			(end -0.7874 -0.4064)
			(stroke
				(width 0.1524)
				(type default)
			)
			(layer "F.SilkS")
		)
		(fp_line
			(start -0.7874 -0.4064)
			(end 0.7874 -0.4064)
			(stroke
				(width 0.1524)
				(type default)
			)
			(layer "F.SilkS")
		)
		(fp_line
			(start 0.67945 0.3048)
			(end 0.120396 0.3048)
			(stroke
				(width 0.1)
				(type default)
			)
			(layer "F.Fab")
		)
		(fp_line
			(start 0.67945 -0.3048)
			(end 0.67945 0.3048)
			(stroke
				(width 0.1)
				(type default)
			)
			(layer "F.Fab")
		)
		(fp_line
			(start 0.12065 -0.2794)
			(end 0.12065 -0.3048)
			(stroke
				(width 0.1)
				(type default)
			)
			(layer "F.Fab")
		)
		(fp_line
			(start 0.12065 -0.3048)
			(end 0.67945 -0.3048)
			(stroke
				(width 0.1)
				(type default)
			)
			(layer "F.Fab")
		)
		(fp_line
			(start 0.120396 0.3048)
			(end 0.120396 0.2794)
			(stroke
				(width 0.1)
				(type default)
			)
			(layer "F.Fab")
		)
		(fp_line
			(start 0.120396 0.2794)
			(end -0.12065 0.2794)
			(stroke
				(width 0.1)
				(type default)
			)
			(layer "F.Fab")
		)
		(fp_line
			(start -0.12065 0.3048)
			(end -0.67945 0.3048)
			(stroke
				(width 0.1)
				(type default)
			)
			(layer "F.Fab")
		)
		(fp_line
			(start -0.12065 0.2794)
			(end -0.12065 0.3048)
			(stroke
				(width 0.1)
				(type default)
			)
			(layer "F.Fab")
		)
		(fp_line
			(start -0.12065 -0.2794)
			(end 0.12065 -0.2794)
			(stroke
				(width 0.1)
				(type default)
			)
			(layer "F.Fab")
		)
		(fp_line
			(start -0.12065 -0.305054)
			(end -0.12065 -0.2794)
			(stroke
				(width 0.1)
				(type default)
			)
			(layer "F.Fab")
		)
		(fp_line
			(start -0.67945 0.3048)
			(end -0.67945 -0.305054)
			(stroke
				(width 0.1)
				(type default)
			)
			(layer "F.Fab")
		)
		(fp_line
			(start -0.67945 -0.305054)
			(end -0.12065 -0.305054)
			(stroke
				(width 0.1)
				(type default)
			)
			(layer "F.Fab")
		)
		(pad "1" smd circle
			(at -0.40005 0 180)
			(size 0 0)
			(layers "F.Cu" "F.Mask" "F.Paste")
			(net "RMII_TXD1_R")
		)
		(pad "2" smd circle
			(at 0.40005 0 180)
			(size 0 0)
			(layers "F.Cu" "F.Mask" "F.Paste")
			(net "RMII_TXD1")
		)
	)
	(footprint ""
		(layer "F.Cu")
		(at 71.374 -19.685 90)
		(property "Reference" "R856"
			(at 0 0 90)
			(layer "F.SilkS")
			(hide yes)
			(effects
				(font
					(size 1.27 1.27)
				)
			)
		)
		(property "Value" ""
			(at 0 0 90)
			(layer "F.Fab")
			(effects
				(font
					(size 1.27 1.27)
				)
			)
		)
		(duplicate_pad_numbers_are_jumpers no)
		(fp_line
			(start 0.7874 -0.4064)
			(end 0.7874 0.4064)
			(stroke
				(width 0.1524)
				(type default)
			)
			(layer "F.SilkS")
		)
		(fp_line
			(start -0.7874 -0.4064)
			(end 0.7874 -0.4064)
			(stroke
				(width 0.1524)
				(type default)
			)
			(layer "F.SilkS")
		)
		(fp_line
			(start 0.7874 0.4064)
			(end -0.7874 0.4064)
			(stroke
				(width 0.1524)
				(type default)
			)
			(layer "F.SilkS")
		)
		(fp_line
			(start -0.7874 0.4064)
			(end -0.7874 -0.4064)
			(stroke
				(width 0.1524)
				(type default)
			)
			(layer "F.SilkS")
		)
		(fp_line
			(start -0.12065 -0.305054)
			(end -0.12065 -0.2794)
			(stroke
				(width 0.1)
				(type default)
			)
			(layer "F.Fab")
		)
		(fp_line
			(start -0.67945 -0.305054)
			(end -0.12065 -0.305054)
			(stroke
				(width 0.1)
				(type default)
			)
			(layer "F.Fab")
		)
		(fp_line
			(start 0.67945 -0.3048)
			(end 0.67945 0.3048)
			(stroke
				(width 0.1)
				(type default)
			)
			(layer "F.Fab")
		)
		(fp_line
			(start 0.12065 -0.3048)
			(end 0.67945 -0.3048)
			(stroke
				(width 0.1)
				(type default)
			)
			(layer "F.Fab")
		)
		(fp_line
			(start 0.12065 -0.2794)
			(end 0.12065 -0.3048)
			(stroke
				(width 0.1)
				(type default)
			)
			(layer "F.Fab")
		)
		(fp_line
			(start -0.12065 -0.2794)
			(end 0.12065 -0.2794)
			(stroke
				(width 0.1)
				(type default)
			)
			(layer "F.Fab")
		)
		(fp_line
			(start 0.120396 0.2794)
			(end -0.12065 0.2794)
			(stroke
				(width 0.1)
				(type default)
			)
			(layer "F.Fab")
		)
		(fp_line
			(start -0.12065 0.2794)
			(end -0.12065 0.3048)
			(stroke
				(width 0.1)
				(type default)
			)
			(layer "F.Fab")
		)
		(fp_line
			(start 0.67945 0.3048)
			(end 0.120396 0.3048)
			(stroke
				(width 0.1)
				(type default)
			)
			(layer "F.Fab")
		)
		(fp_line
			(start 0.120396 0.3048)
			(end 0.120396 0.2794)
			(stroke
				(width 0.1)
				(type default)
			)
			(layer "F.Fab")
		)
		(fp_line
			(start -0.12065 0.3048)
			(end -0.67945 0.3048)
			(stroke
				(width 0.1)
				(type default)
			)
			(layer "F.Fab")
		)
		(fp_line
			(start -0.67945 0.3048)
			(end -0.67945 -0.305054)
			(stroke
				(width 0.1)
				(type default)
			)
			(layer "F.Fab")
		)
		(pad "1" smd circle
			(at -0.40005 0 90)
			(size 0 0)
			(layers "F.Cu" "F.Mask" "F.Paste")
			(net "P1V8_AUX")
		)
		(pad "2" smd circle
			(at 0.40005 0 90)
			(size 0 0)
			(layers "F.Cu" "F.Mask" "F.Paste")
			(net "FM_BOARD_BMC_REV_ID1")
		)
	)
)
